# T6G (Grand Teton) — schematic netlist excerpt (pin names and nets, part order shuffled) for the footprints in the layout excerpt that follows; sources: Cadence DE-HDL packaged netlist, KiCad conversion of 04192023_DAF0TMB3IC0_F0TG_MB_C_brd_V02_OCP.brd

R1240  Q_RES  1K 1% CHIP  pkg 0402LF  page 258 : A = ADC128_2_A1 ; B = GND
R3034  Q_RES  4.7K 5% CHIP  pkg 0402LF  page 127 : A = P3V3_AUX ; B = FM_SMB_2_ALERT_GPU

(kicad_pcb
	(version 20260206)
	(generator "pcbnew")
	(generator_version "10.0")
	(general
		(thickness 1.6)
		(legacy_teardrops no)
	)
	(paper "A4")
	(title_block
		(title "04192023_DAF0TMB3IC0_F0TG_MB_C_brd_V02_OCP.brd")
		(comment 1 "Grand Teton / footprints 5236-5237 of 8354")
	)
	(layers
		(0 "F.Cu" signal "TOP")
		(4 "In1.Cu" signal "GND")
		(6 "In2.Cu" signal "IN1")
		(8 "In3.Cu" signal "GND1")
		(10 "In4.Cu" signal "IN2")
		(12 "In5.Cu" signal "GND2")
		(14 "In6.Cu" signal "IN3")
		(16 "In7.Cu" signal "GND3")
		(18 "In8.Cu" signal "VCC")
		(20 "In9.Cu" signal "VCC1")
		(22 "In10.Cu" signal "GND4")
		(24 "In11.Cu" signal "IN4")
		(26 "In12.Cu" signal "GND5")
		(28 "In13.Cu" signal "IN5")
		(30 "In14.Cu" signal "GND6")
		(32 "In15.Cu" signal "IN6")
		(34 "In16.Cu" signal "GND7")
		(2 "B.Cu" signal "BOTTOM")
		(9 "F.Adhes" user "F.Adhesive")
		(11 "B.Adhes" user "B.Adhesive")
		(13 "F.Paste" user "Package Geometry/Pastemask Top")
		(15 "B.Paste" user "Package Geometry/Pastemask Bottom")
		(5 "F.SilkS" user "Ref Des/Silkscreen Top")
		(7 "B.SilkS" user "Ref Des/Silkscreen Bottom")
		(1 "F.Mask" user "Board Geometry/Soldermask Top")
		(3 "B.Mask" user "Board Geometry/Soldermask Bottom")
		(17 "Dwgs.User" user "User.Drawings")
		(19 "Cmts.User" user "User.Comments")
		(21 "Eco1.User" user "User.Eco1")
		(23 "Eco2.User" user "User.Eco2")
		(25 "Edge.Cuts" user "Board Geometry/Outline")
		(27 "Margin" user)
		(31 "F.CrtYd" user "Package Geometry/Place Bound Top")
		(29 "B.CrtYd" user "Package Geometry/Place Bound Bottom")
		(35 "F.Fab" user "Ref Des/Assembly Top")
		(33 "B.Fab" user "Ref Des/Assembly Bottom")
	)
	(footprint ""
		(layer "B.Cu")
		(at 103.759 -418.592 90)
		(property "Reference" "R3034"
			(at 0 0 90)
			(layer "B.SilkS")
			(hide yes)
			(effects
				(font
					(size 1.27 1.27)
				)
				(justify mirror)
			)
		)
		(property "Value" ""
			(at 0 0 90)
			(layer "B.Fab")
			(effects
				(font
					(size 1.27 1.27)
				)
				(justify mirror)
			)
		)
		(duplicate_pad_numbers_are_jumpers no)
		(fp_line
			(start 0.7874 -0.4064)
			(end -0.7874 -0.4064)
			(stroke
				(width 0.1524)
				(type default)
			)
			(layer "B.SilkS")
		)
		(fp_line
			(start -0.7874 -0.4064)
			(end -0.7874 0.4064)
			(stroke
				(width 0.1524)
				(type default)
			)
			(layer "B.SilkS")
		)
		(fp_line
			(start 0.7874 0.4064)
			(end 0.7874 -0.4064)
			(stroke
				(width 0.1524)
				(type default)
			)
			(layer "B.SilkS")
		)
		(fp_line
			(start -0.7874 0.4064)
			(end 0.7874 0.4064)
			(stroke
				(width 0.1524)
				(type default)
			)
			(layer "B.SilkS")
		)
		(fp_line
			(start 0.67945 -0.305054)
			(end 0.12065 -0.305054)
			(stroke
				(width 0.1)
				(type default)
			)
			(layer "B.Fab")
		)
		(fp_line
			(start 0.12065 -0.305054)
			(end 0.12065 -0.2794)
			(stroke
				(width 0.1)
				(type default)
			)
			(layer "B.Fab")
		)
		(fp_line
			(start -0.12065 -0.3048)
			(end -0.67945 -0.3048)
			(stroke
				(width 0.1)
				(type default)
			)
			(layer "B.Fab")
		)
		(fp_line
			(start -0.67945 -0.3048)
			(end -0.67945 0.3048)
			(stroke
				(width 0.1)
				(type default)
			)
			(layer "B.Fab")
		)
		(fp_line
			(start 0.12065 -0.2794)
			(end -0.12065 -0.2794)
			(stroke
				(width 0.1)
				(type default)
			)
			(layer "B.Fab")
		)
		(fp_line
			(start -0.12065 -0.2794)
			(end -0.12065 -0.3048)
			(stroke
				(width 0.1)
				(type default)
			)
			(layer "B.Fab")
		)
		(fp_line
			(start 0.12065 0.2794)
			(end 0.12065 0.3048)
			(stroke
				(width 0.1)
				(type default)
			)
			(layer "B.Fab")
		)
		(fp_line
			(start -0.120396 0.2794)
			(end 0.12065 0.2794)
			(stroke
				(width 0.1)
				(type default)
			)
			(layer "B.Fab")
		)
		(fp_line
			(start 0.67945 0.3048)
			(end 0.67945 -0.305054)
			(stroke
				(width 0.1)
				(type default)
			)
			(layer "B.Fab")
		)
		(fp_line
			(start 0.12065 0.3048)
			(end 0.67945 0.3048)
			(stroke
				(width 0.1)
				(type default)
			)
			(layer "B.Fab")
		)
		(fp_line
			(start -0.120396 0.3048)
			(end -0.120396 0.2794)
			(stroke
				(width 0.1)
				(type default)
			)
			(layer "B.Fab")
		)
		(fp_line
			(start -0.67945 0.3048)
			(end -0.120396 0.3048)
			(stroke
				(width 0.1)
				(type default)
			)
			(layer "B.Fab")
		)
		(pad "1" smd circle
			(at 0.40005 0 270)
			(size 0 0)
			(layers "B.Cu" "B.Mask" "B.Paste")
			(net "P3V3_AUX")
		)
		(pad "2" smd circle
			(at -0.40005 0 270)
			(size 0 0)
			(layers "B.Cu" "B.Mask" "B.Paste")
			(net "FM_SMB_2_ALERT_GPU")
		)
	)
	(footprint ""
		(layer "B.Cu")
		(at 213.616286 -329.201272)
		(property "Reference" "R1240"
			(at 0 0 0)
			(layer "B.SilkS")
			(hide yes)
			(effects
				(font
					(size 1.27 1.27)
				)
				(justify mirror)
			)
		)
		(property "Value" ""
			(at 0 0 0)
			(layer "B.Fab")
			(effects
				(font
					(size 1.27 1.27)
				)
				(justify mirror)
			)
		)
		(duplicate_pad_numbers_are_jumpers no)
		(fp_line
			(start -0.7874 -0.4064)
			(end -0.7874 0.4064)
			(stroke
				(width 0.1524)
				(type default)
			)
			(layer "B.SilkS")
		)
		(fp_line
			(start -0.7874 0.4064)
			(end 0.7874 0.4064)
			(stroke
				(width 0.1524)
				(type default)
			)
			(layer "B.SilkS")
		)
		(fp_line
			(start 0.7874 -0.4064)
			(end -0.7874 -0.4064)
			(stroke
				(width 0.1524)
				(type default)
			)
			(layer "B.SilkS")
		)
		(fp_line
			(start 0.7874 0.4064)
			(end 0.7874 -0.4064)
			(stroke
				(width 0.1524)
				(type default)
			)
			(layer "B.SilkS")
		)
		(fp_line
			(start -0.67945 -0.3048)
			(end -0.67945 0.3048)
			(stroke
				(width 0.1)
				(type default)
			)
			(layer "B.Fab")
		)
		(fp_line
			(start -0.67945 0.3048)
			(end -0.120396 0.3048)
			(stroke
				(width 0.1)
				(type default)
			)
			(layer "B.Fab")
		)
		(fp_line
			(start -0.12065 -0.3048)
			(end -0.67945 -0.3048)
			(stroke
				(width 0.1)
				(type default)
			)
			(layer "B.Fab")
		)
		(fp_line
			(start -0.12065 -0.2794)
			(end -0.12065 -0.3048)
			(stroke
				(width 0.1)
				(type default)
			)
			(layer "B.Fab")
		)
		(fp_line
			(start -0.120396 0.2794)
			(end 0.12065 0.2794)
			(stroke
				(width 0.1)
				(type default)
			)
			(layer "B.Fab")
		)
		(fp_line
			(start -0.120396 0.3048)
			(end -0.120396 0.2794)
			(stroke
				(width 0.1)
				(type default)
			)
			(layer "B.Fab")
		)
		(fp_line
			(start 0.12065 -0.305054)
			(end 0.12065 -0.2794)
			(stroke
				(width 0.1)
				(type default)
			)
			(layer "B.Fab")
		)
		(fp_line
			(start 0.12065 -0.2794)
			(end -0.12065 -0.2794)
			(stroke
				(width 0.1)
				(type default)
			)
			(layer "B.Fab")
		)
		(fp_line
			(start 0.12065 0.2794)
			(end 0.12065 0.3048)
			(stroke
				(width 0.1)
				(type default)
			)
			(layer "B.Fab")
		)
		(fp_line
			(start 0.12065 0.3048)
			(end 0.67945 0.3048)
			(stroke
				(width 0.1)
				(type default)
			)
			(layer "B.Fab")
		)
		(fp_line
			(start 0.67945 -0.305054)
			(end 0.12065 -0.305054)
			(stroke
				(width 0.1)
				(type default)
			)
			(layer "B.Fab")
		)
		(fp_line
			(start 0.67945 0.3048)
			(end 0.67945 -0.305054)
			(stroke
				(width 0.1)
				(type default)
			)
			(layer "B.Fab")
		)
		(pad "1" smd circle
			(at 0.40005 0 180)
			(size 0 0)
			(layers "B.Cu" "B.Mask" "B.Paste")
			(net "ADC128_2_A1")
		)
		(pad "2" smd circle
			(at -0.40005 0 180)
			(size 0 0)
			(layers "B.Cu" "B.Mask" "B.Paste")
			(net "GND")
		)
	)
)
